# S9S_MB_2U (Grand Teton) — schematic netlist excerpt (pin names and nets, part order shuffled) for the footprints in the layout excerpt that follows; sources: Cadence DE-HDL packaged netlist, KiCad conversion of 03242023_DA0F0TMBIJ0_F0T_Motherboard_J_brd_V01_OCP.brd

C297  Q_CAP  22UF 4V 20% X6S  pkg C0402  page 77 : A = PVCCIN_CPU1 ; B = GND
R1367  Q_RES  100 1% CHIP  pkg 0402LF  page 239 : A = JTAG_DBP_PRDY_N ; B = JTAG_DBP_PRDY_R_N

(kicad_pcb
	(version 20260206)
	(generator "pcbnew")
	(generator_version "10.0")
	(general
		(thickness 1.6)
		(legacy_teardrops no)
	)
	(paper "A4")
	(title_block
		(title "03242023_DA0F0TMBIJ0_F0T_Motherboard_J_brd_V01_OCP.brd")
		(comment 1 "Grand Teton / footprints 2547-2548 of 6105")
	)
	(layers
		(0 "F.Cu" signal "TOP")
		(4 "In1.Cu" signal "GND")
		(6 "In2.Cu" signal "IN1")
		(8 "In3.Cu" signal "GND1")
		(10 "In4.Cu" signal "IN2")
		(12 "In5.Cu" signal "GND2")
		(14 "In6.Cu" signal "IN3")
		(16 "In7.Cu" signal "GND3")
		(18 "In8.Cu" signal "VCC")
		(20 "In9.Cu" signal "VCC1")
		(22 "In10.Cu" signal "GND4")
		(24 "In11.Cu" signal "IN4")
		(26 "In12.Cu" signal "GND5")
		(28 "In13.Cu" signal "IN5")
		(30 "In14.Cu" signal "GND6")
		(32 "In15.Cu" signal "IN6")
		(34 "In16.Cu" signal "GND7")
		(2 "B.Cu" signal "BOTTOM")
		(9 "F.Adhes" user "F.Adhesive")
		(11 "B.Adhes" user "B.Adhesive")
		(13 "F.Paste" user "Package Geometry/Pastemask Top")
		(15 "B.Paste" user "Package Geometry/Pastemask Bottom")
		(5 "F.SilkS" user "Ref Des/Silkscreen Top")
		(7 "B.SilkS" user "Ref Des/Silkscreen Bottom")
		(1 "F.Mask" user "Board Geometry/Soldermask Top")
		(3 "B.Mask" user "Board Geometry/Soldermask Bottom")
		(17 "Dwgs.User" user "User.Drawings")
		(19 "Cmts.User" user "User.Comments")
		(21 "Eco1.User" user "User.Eco1")
		(23 "Eco2.User" user "User.Eco2")
		(25 "Edge.Cuts" user "Board Geometry/Outline")
		(27 "Margin" user)
		(31 "F.CrtYd" user "Package Geometry/Place Bound Top")
		(29 "B.CrtYd" user "Package Geometry/Place Bound Bottom")
		(35 "F.Fab" user "Ref Des/Assembly Top")
		(33 "B.Fab" user "Ref Des/Assembly Bottom")
	)
	(footprint ""
		(layer "F.Cu")
		(at 117.526816 -251.375672 90)
		(property "Reference" "C297"
			(at 0 0 90)
			(layer "F.SilkS")
			(hide yes)
			(effects
				(font
					(size 1.27 1.27)
				)
			)
		)
		(property "Value" ""
			(at 0 0 90)
			(layer "F.Fab")
			(effects
				(font
					(size 1.27 1.27)
				)
			)
		)
		(duplicate_pad_numbers_are_jumpers no)
		(fp_line
			(start 0.7874 -0.4064)
			(end 0.7874 0.4064)
			(stroke
				(width 0.1524)
				(type default)
			)
			(layer "F.SilkS")
		)
		(fp_line
			(start -0.7874 -0.4064)
			(end 0.7874 -0.4064)
			(stroke
				(width 0.1524)
				(type default)
			)
			(layer "F.SilkS")
		)
		(fp_line
			(start 0.7874 0.4064)
			(end -0.7874 0.4064)
			(stroke
				(width 0.1524)
				(type default)
			)
			(layer "F.SilkS")
		)
		(fp_line
			(start -0.7874 0.4064)
			(end -0.7874 -0.4064)
			(stroke
				(width 0.1524)
				(type default)
			)
			(layer "F.SilkS")
		)
		(fp_line
			(start -0.12065 -0.305054)
			(end -0.12065 -0.2794)
			(stroke
				(width 0.1)
				(type default)
			)
			(layer "F.Fab")
		)
		(fp_line
			(start -0.67945 -0.305054)
			(end -0.12065 -0.305054)
			(stroke
				(width 0.1)
				(type default)
			)
			(layer "F.Fab")
		)
		(fp_line
			(start 0.67945 -0.3048)
			(end 0.67945 0.3048)
			(stroke
				(width 0.1)
				(type default)
			)
			(layer "F.Fab")
		)
		(fp_line
			(start 0.12065 -0.3048)
			(end 0.67945 -0.3048)
			(stroke
				(width 0.1)
				(type default)
			)
			(layer "F.Fab")
		)
		(fp_line
			(start 0.12065 -0.2794)
			(end 0.12065 -0.3048)
			(stroke
				(width 0.1)
				(type default)
			)
			(layer "F.Fab")
		)
		(fp_line
			(start -0.12065 -0.2794)
			(end 0.12065 -0.2794)
			(stroke
				(width 0.1)
				(type default)
			)
			(layer "F.Fab")
		)
		(fp_line
			(start 0.120396 0.2794)
			(end -0.12065 0.2794)
			(stroke
				(width 0.1)
				(type default)
			)
			(layer "F.Fab")
		)
		(fp_line
			(start -0.12065 0.2794)
			(end -0.12065 0.3048)
			(stroke
				(width 0.1)
				(type default)
			)
			(layer "F.Fab")
		)
		(fp_line
			(start 0.67945 0.3048)
			(end 0.120396 0.3048)
			(stroke
				(width 0.1)
				(type default)
			)
			(layer "F.Fab")
		)
		(fp_line
			(start 0.120396 0.3048)
			(end 0.120396 0.2794)
			(stroke
				(width 0.1)
				(type default)
			)
			(layer "F.Fab")
		)
		(fp_line
			(start -0.12065 0.3048)
			(end -0.67945 0.3048)
			(stroke
				(width 0.1)
				(type default)
			)
			(layer "F.Fab")
		)
		(fp_line
			(start -0.67945 0.3048)
			(end -0.67945 -0.305054)
			(stroke
				(width 0.1)
				(type default)
			)
			(layer "F.Fab")
		)
		(pad "1" smd circle
			(at -0.40005 0 90)
			(size 0 0)
			(layers "F.Cu" "F.Mask" "F.Paste")
			(net "PVCCIN_CPU1")
		)
		(pad "2" smd circle
			(at 0.40005 0 90)
			(size 0 0)
			(layers "F.Cu" "F.Mask" "F.Paste")
			(net "GND")
		)
	)
	(footprint ""
		(layer "F.Cu")
		(at 378.303536 -105.483152 -90)
		(property "Reference" "R1367"
			(at 0 0 270)
			(layer "F.SilkS")
			(hide yes)
			(effects
				(font
					(size 1.27 1.27)
				)
			)
		)
		(property "Value" ""
			(at 0 0 270)
			(layer "F.Fab")
			(effects
				(font
					(size 1.27 1.27)
				)
			)
		)
		(duplicate_pad_numbers_are_jumpers no)
		(fp_line
			(start -0.7874 0.4064)
			(end -0.7874 -0.4064)
			(stroke
				(width 0.1524)
				(type default)
			)
			(layer "F.SilkS")
		)
		(fp_line
			(start 0.7874 0.4064)
			(end -0.7874 0.4064)
			(stroke
				(width 0.1524)
				(type default)
			)
			(layer "F.SilkS")
		)
		(fp_line
			(start -0.7874 -0.4064)
			(end 0.7874 -0.4064)
			(stroke
				(width 0.1524)
				(type default)
			)
			(layer "F.SilkS")
		)
		(fp_line
			(start 0.7874 -0.4064)
			(end 0.7874 0.4064)
			(stroke
				(width 0.1524)
				(type default)
			)
			(layer "F.SilkS")
		)
		(fp_line
			(start -0.67945 0.3048)
			(end -0.67945 -0.305054)
			(stroke
				(width 0.1)
				(type default)
			)
			(layer "F.Fab")
		)
		(fp_line
			(start -0.12065 0.3048)
			(end -0.67945 0.3048)
			(stroke
				(width 0.1)
				(type default)
			)
			(layer "F.Fab")
		)
		(fp_line
			(start 0.120396 0.3048)
			(end 0.120396 0.2794)
			(stroke
				(width 0.1)
				(type default)
			)
			(layer "F.Fab")
		)
		(fp_line
			(start 0.67945 0.3048)
			(end 0.120396 0.3048)
			(stroke
				(width 0.1)
				(type default)
			)
			(layer "F.Fab")
		)
		(fp_line
			(start -0.12065 0.2794)
			(end -0.12065 0.3048)
			(stroke
				(width 0.1)
				(type default)
			)
			(layer "F.Fab")
		)
		(fp_line
			(start 0.120396 0.2794)
			(end -0.12065 0.2794)
			(stroke
				(width 0.1)
				(type default)
			)
			(layer "F.Fab")
		)
		(fp_line
			(start -0.12065 -0.2794)
			(end 0.12065 -0.2794)
			(stroke
				(width 0.1)
				(type default)
			)
			(layer "F.Fab")
		)
		(fp_line
			(start 0.12065 -0.2794)
			(end 0.12065 -0.3048)
			(stroke
				(width 0.1)
				(type default)
			)
			(layer "F.Fab")
		)
		(fp_line
			(start 0.12065 -0.3048)
			(end 0.67945 -0.3048)
			(stroke
				(width 0.1)
				(type default)
			)
			(layer "F.Fab")
		)
		(fp_line
			(start 0.67945 -0.3048)
			(end 0.67945 0.3048)
			(stroke
				(width 0.1)
				(type default)
			)
			(layer "F.Fab")
		)
		(fp_line
			(start -0.67945 -0.305054)
			(end -0.12065 -0.305054)
			(stroke
				(width 0.1)
				(type default)
			)
			(layer "F.Fab")
		)
		(fp_line
			(start -0.12065 -0.305054)
			(end -0.12065 -0.2794)
			(stroke
				(width 0.1)
				(type default)
			)
			(layer "F.Fab")
		)
		(pad "1" smd circle
			(at -0.40005 0 270)
			(size 0 0)
			(layers "F.Cu" "F.Mask" "F.Paste")
			(net "JTAG_DBP_PRDY_N")
		)
		(pad "2" smd circle
			(at 0.40005 0 270)
			(size 0 0)
			(layers "F.Cu" "F.Mask" "F.Paste")
			(net "JTAG_DBP_PRDY_R_N")
		)
	)
)
